#ISCELL
  mstr_misc dns *
  *
#ISCELL
  pure_quanta quanta_title_block_c *
  *
#CELL
  pure_quanta 9zxl0451ekilft *
  page200_i1
#CELL
  pure_quanta q_cap *
  page200_i10
#CELL
  pure_quanta q_res *
  page200_i11
#ISCELL
  logical_power universal_gnd *
  page200_i12
#CELL
  pure_quanta q_cap *
  page200_i17
#ISCELL
  logical_power universal_gnd *
  page200_i21
#ISCELL
  logical_power universal_gnd *
  page200_i22
#ISCELL
  logical_power universal_power *
  page200_i23
#ISCELL
  logical_power universal_power *
  page200_i24
#ISCELL
  logical_power universal_power *
  page200_i25
#ISCELL
  logical_power universal_power *
  page200_i26
#ISCELL
  logical_power universal_power *
  page200_i27
#ISCELL
  logical_power universal_power *
  page200_i28
#ISCELL
  logical_power universal_power *
  page200_i29
#CELL
  pure_quanta q_res *
  page200_i30
#CELL
  pure_quanta q_res *
  page200_i31
#ISCELL
  logical_power universal_power *
  page200_i32
#ISCELL
  logical_power universal_gnd *
  page200_i33
#ISCELL
  standard offpage *
  page200_i34
#ISCELL
  standard offpage *
  page200_i35
#ISCELL
  standard offpage *
  page200_i36
#ISCELL
  standard offpage *
  page200_i37
#ISCELL
  standard offpage *
  page200_i38
#CELL
  pure_quanta q_res *
  page200_i39
#CELL
  pure_quanta q_res *
  page200_i4
#ISCELL
  standard offpage *
  page200_i40
#ISCELL
  standard offpage *
  page200_i41
#ISCELL
  standard offpage *
  page200_i42
#ISCELL
  standard offpage *
  page200_i43
#ISCELL
  standard offpage *
  page200_i44
#ISCELL
  standard offpage *
  page200_i45
#CELL
  pure_quanta q_res *
  page200_i48
#CELL
  pure_quanta q_res *
  page200_i49
#CELL
  pure_quanta q_cap *
  page200_i5
#ISCELL
  logical_power universal_power *
  page200_i50
#ISCELL
  logical_power universal_gnd *
  page200_i51
#ISCELL
  standard offpage *
  page200_i52
#ISCELL
  standard offpage *
  page200_i53
#CELL
  pure_quanta q_cap *
  page200_i54
#CELL
  pure_quanta q_cap *
  page200_i55
#CELL
  pure_quanta q_cap *
  page200_i56
#CELL
  pure_quanta q_cap *
  page200_i57
#CELL
  pure_quanta q_cap *
  page200_i58
#CELL
  pure_quanta q_cap *
  page200_i59
#ISCELL
  standard offpage *
  page200_i62
#ISCELL
  standard offpage *
  page200_i63
#ISCELL
  standard offpage *
  page200_i66
#CELL
  pure_quanta q_res *
  page200_i69
#ISCELL
  logical_power universal_power *
  page200_i7
#ISCELL
  logical_power universal_power *
  page200_i70
#CELL
  pure_quanta q_cap *
  page200_i71
#ISCELL
  standard offpage *
  page200_i72
#ISCELL
  standard offpage *
  page200_i73
#CELL
  pure_quanta q_res *
  page200_i74
#CELL
  pure_quanta q_res *
  page200_i75
#CELL
  pure_quanta q_res *
  page200_i76
#CELL
  pure_quanta q_res *
  page200_i77
#CELL
  pure_quanta q_res *
  page200_i78
#CELL
  pure_quanta q_res *
  page200_i79
#ISCELL
  logical_power universal_gnd *
  page200_i8
#ISCELL
  logical_power universal_power *
  page200_i80
#CELL
  pure_quanta q_inductor *
  page200_i81
#CELL
  pure_quanta q_inductor *
  page200_i82
